FILE_TYPE = MACRO_DRAWING;
SET COLOR_WIRE YELLOW;
SET COLOR_PROP ORANGE;
SET COLOR_DOT WHITE;
SET COLOR_ARC YELLOW;
SET COLOR_BODY GREEN;
SET COLOR_NOTE PURPLE;
SET PROP_DISPLAY VALUE;
SET PAGE_NUMBER P235;
FORCEADD UNIVERSAL_GND..1
(-2225 5200);
FORCEPROP 3 LASTPIN (-2225 5250) SIG_NAME GND\g
J 0
(-2215 5260);
DISPLAY 0.659574 (-2215 5260);
PAINT MONO (-2215 5260);
DISPLAY INVISIBLE (-2215 5260);
FORCEPROP 2 LAST CDS_LIB logical_power
J 0
(-2225 5200);
DISPLAY INVISIBLE (-2225 5200);
FORCEPROP 1 LAST HDL_POWER GND
J 1
(-2200 5125);
DISPLAY 0.872340 (-2200 5125);
PAINT GREEN (-2200 5125);
DISPLAY INVISIBLE (-2200 5125);
FORCEPROP 1 LAST PATH I1
J 0
(-2150 5200);
DISPLAY 0.872340 (-2150 5200);
PAINT AQUA (-2150 5200);
DISPLAY INVISIBLE (-2150 5200);
FORCEADD UNIVERSAL_GND..1
(-750 4275);
FORCEPROP 3 LASTPIN (-750 4325) SIG_NAME GND\g
J 0
(-740 4335);
DISPLAY 0.659574 (-740 4335);
PAINT MONO (-740 4335);
DISPLAY INVISIBLE (-740 4335);
FORCEPROP 2 LAST CDS_LIB logical_power
J 0
(-750 4275);
DISPLAY INVISIBLE (-750 4275);
FORCEPROP 1 LAST HDL_POWER GND
J 1
(-725 4200);
DISPLAY 0.872340 (-725 4200);
PAINT GREEN (-725 4200);
DISPLAY INVISIBLE (-725 4200);
FORCEPROP 1 LAST PATH I10
J 0
(-675 4275);
DISPLAY 0.872340 (-675 4275);
PAINT AQUA (-675 4275);
DISPLAY INVISIBLE (-675 4275);
FORCEADD Q_RES..2
(-750 4850);
FORCEPROP 1 LAST PART_NUMBER CS21002FB06
J 0
(-710 4725);
DISPLAY 0.978723 (-710 4725);
DISPLAY INVISIBLE (-710 4725);
FORCEPROP 1 LAST VALUE 1K
J 0
(-705 4925);
DISPLAY 0.978723 (-705 4925);
FORCEPROP 1 LAST PACK_TYPE 0402LF
J 0
(-710 4675);
DISPLAY 0.978723 (-710 4675);
FORCEPROP 1 LAST MATERIAL CHIP
J 0
(-710 4775);
DISPLAY 0.978723 (-710 4775);
FORCEPROP 1 LAST WATTAGE 1/16W
J 0
(-710 4825);
DISPLAY 0.978723 (-710 4825);
FORCEPROP 1 LAST TOLERANCE 1%
J 0
(-705 4875);
DISPLAY 0.978723 (-705 4875);
FORCEPROP 1 LAST $LOCATION R4623
J 0
(-705 4975);
DISPLAY 0.978723 (-705 4975);
FORCEPROP 1 LASTPIN (-750 4950) $PN 1
J 0
(-745 4912);
DISPLAY 0.787234 (-745 4912);
PAINT MONO (-745 4912);
FORCEPROP 1 LASTPIN (-750 4750) $PN 2
J 0
(-745 4760);
DISPLAY 0.787234 (-745 4760);
PAINT MONO (-745 4760);
FORCEPROP 2 LAST CDS_LIB pure_quanta
J 0
(-750 4850);
PAINT MONO (-750 4850);
DISPLAY INVISIBLE (-750 4850);
FORCEPROP 1 LAST PATH I11
J 0
(-700 5025);
DISPLAY 0.978723 (-700 5025);
PAINT WHITE (-700 5025);
DISPLAY INVISIBLE (-700 5025);
FORCEPROP 2 LAST CDS_LOCATION R4623
J 0
(-800 5050);
DISPLAY 1.021277 (-800 5050);
DISPLAY INVISIBLE (-800 5050);
FORCEPROP 0 LAST $SEC 1
J 0
(-700 5025);
DISPLAY 0.680851 (-700 5025);
PAINT MONO (-700 5025);
DISPLAY INVISIBLE (-700 5025);
FORCEPROP 2 LAST CDS_SEC 1
J 0
(-800 5050);
DISPLAY 1.021277 (-800 5050);
DISPLAY INVISIBLE (-800 5050);
FORCEADD UNIVERSAL_POWER..1
(-750 5050);
FORCEPROP 3 LASTPIN (-750 5000) SIG_NAME P3V3_AUX\g
J 0
(-740 5010);
DISPLAY 0.659574 (-740 5010);
PAINT MONO (-740 5010);
DISPLAY INVISIBLE (-740 5010);
FORCEPROP 1 LAST HDL_POWER P3V3_AUX
J 1
(-750 5100);
DISPLAY 0.872340 (-750 5100);
PAINT GREEN (-750 5100);
FORCEPROP 2 LAST CDS_LIB logical_power
J 0
(-750 5050);
DISPLAY INVISIBLE (-750 5050);
FORCEPROP 1 LAST PATH I12
J 0
(-700 5075);
DISPLAY 0.872340 (-700 5075);
PAINT AQUA (-700 5075);
DISPLAY INVISIBLE (-700 5075);
FORCEADD CONN3_210HP1030BR1..1
(200 4550);
PAINT AQUA (200 4550);
FORCEPROP 1 LAST PART_NUMBER DFHD03MS213
J 0
(150 4725);
DISPLAY 0.723404 (150 4725);
PAINT WHITE (150 4725);
DISPLAY INVISIBLE (150 4725);
FORCEPROP 2 LAST PART_TYPE THLF
J 0
(150 4875);
DISPLAY 1.021277 (150 4875);
FORCEPROP 1 LAST MATERIAL IO
J 0
(137 4674);
DISPLAY 0.723404 (137 4674);
PAINT SKYBLUE (137 4674);
FORCEPROP 2 LAST VALUE CONN3_210-HP1-030BR1
J 0
(150 4825);
DISPLAY 0.723404 (150 4825);
PAINT AQUA (150 4825);
FORCEPROP 1 LAST $LOCATION JP16
J 0
(150 4775);
DISPLAY 0.723404 (150 4775);
PAINT AQUA (150 4775);
FORCEPROP 0 LASTPIN (0 4600) $PN 1
J 2
(-10 4610);
DISPLAY 0.680851 (-10 4610);
PAINT MONO (-10 4610);
FORCEPROP 0 LASTPIN (0 4550) $PN 2
J 2
(-10 4560);
DISPLAY 0.680851 (-10 4560);
PAINT MONO (-10 4560);
FORCEPROP 0 LASTPIN (0 4500) $PN 3
J 2
(-10 4510);
DISPLAY 0.680851 (-10 4510);
PAINT MONO (-10 4510);
FORCEPROP 2 LAST CDS_LIB pure_quanta
J 0
(200 4550);
DISPLAY INVISIBLE (200 4550);
FORCEPROP 1 LAST CDS_LMAN_SYM_OUTLINE -50,100,50,-100
J 0
(200 4550);
DISPLAY 0.468085 (200 4550);
PAINT GREEN (200 4550);
DISPLAY INVISIBLE (200 4550);
FORCEPROP 1 LAST NEEDS_NO_SIZE TRUE
J 0
(200 4550);
DISPLAY 0.723404 (200 4550);
PAINT GREEN (200 4550);
DISPLAY INVISIBLE (200 4550);
FORCEPROP 1 LAST PATH I13
J 0
(200 4550);
DISPLAY 0.723404 (200 4550);
PAINT GREEN (200 4550);
DISPLAY INVISIBLE (200 4550);
FORCEPROP 0 LAST CDS_LOCATION JP16
J 0
(150 4925);
DISPLAY 1.021277 (150 4925);
DISPLAY INVISIBLE (150 4925);
FORCEPROP 0 LAST $SEC 1
J 0
(150 4925);
DISPLAY 0.680851 (150 4925);
PAINT MONO (150 4925);
DISPLAY INVISIBLE (150 4925);
FORCEPROP 0 LAST CDS_SEC 1
J 0
(150 4925);
DISPLAY 1.021277 (150 4925);
DISPLAY INVISIBLE (150 4925);
FORCEADD Q_RES..1
(-500 5775);
FORCEPROP 1 LAST PART_NUMBER CS00002JB13
J 0
(-375 5800);
DISPLAY 0.319149 (-375 5800);
DISPLAY INVISIBLE (-375 5800);
FORCEPROP 1 LAST WATTAGE 1/16W
J 2
(-200 5825);
DISPLAY 0.319149 (-200 5825);
FORCEPROP 1 LAST VALUE 0
J 2
(-350 5775);
DISPLAY 0.404255 (-350 5775);
FORCEPROP 1 LAST TOLERANCE 5%
J 0
(-325 5775);
DISPLAY 0.404255 (-325 5775);
FORCEPROP 1 LAST PACK_TYPE 0402LF
J 0
(-375 5825);
DISPLAY 0.319149 (-375 5825);
FORCEPROP 1 LAST MATERIAL CHIP
J 0
(-250 5775);
DISPLAY 0.404255 (-250 5775);
FORCEPROP 1 LAST $LOCATION R4624
J 0
(-800 5775);
DISPLAY 0.978723 (-800 5775);
FORCEPROP 1 LASTPIN (-600 5775) $PN 1
J 0
(-588 5787);
DISPLAY 0.787234 (-588 5787);
PAINT MONO (-588 5787);
FORCEPROP 1 LASTPIN (-400 5775) $PN 2
J 0
(-438 5787);
DISPLAY 0.787234 (-438 5787);
PAINT MONO (-438 5787);
FORCEPROP 2 LAST CDS_LIB pure_quanta
J 0
(-500 5775);
DISPLAY INVISIBLE (-500 5775);
FORCEPROP 1 LAST PATH I14
J 0
(-550 5925);
DISPLAY 0.978723 (-550 5925);
PAINT WHITE (-550 5925);
DISPLAY INVISIBLE (-550 5925);
FORCEPROP 0 LAST CDS_LOCATION R4624
J 0
(-200 5850);
DISPLAY 1.021277 (-200 5850);
DISPLAY INVISIBLE (-200 5850);
FORCEPROP 0 LAST $SEC 1
J 0
(-200 5850);
DISPLAY 0.680851 (-200 5850);
PAINT MONO (-200 5850);
DISPLAY INVISIBLE (-200 5850);
FORCEPROP 0 LAST CDS_SEC 1
J 0
(-200 5850);
DISPLAY 1.021277 (-200 5850);
DISPLAY INVISIBLE (-200 5850);
FORCEADD Q_RES..1
(-250 6225);
FORCEPROP 1 LAST PART_NUMBER CS00002JB13
J 0
(-125 6250);
DISPLAY 0.319149 (-125 6250);
DISPLAY INVISIBLE (-125 6250);
FORCEPROP 1 LAST MATERIAL CHIP
J 0
(-75 6225);
DISPLAY 0.404255 (-75 6225);
FORCEPROP 1 LAST VALUE 0
J 2
(-100 6225);
DISPLAY 0.404255 (-100 6225);
FORCEPROP 1 LAST $LOCATION R4629
J 0
(-550 6225);
DISPLAY 0.978723 (-550 6225);
FORCEPROP 1 LASTPIN (-350 6225) $PN 1
J 0
(-338 6237);
DISPLAY 0.787234 (-338 6237);
PAINT MONO (-338 6237);
FORCEPROP 1 LASTPIN (-150 6225) $PN 2
J 0
(-188 6237);
DISPLAY 0.787234 (-188 6237);
PAINT MONO (-188 6237);
FORCEPROP 2 LAST CDS_LIB pure_quanta
J 0
(-250 6225);
DISPLAY INVISIBLE (-250 6225);
FORCEPROP 1 LAST PACK_TYPE 0402LF
J 0
(-125 6275);
DISPLAY 0.319149 (-125 6275);
DISPLAY INVISIBLE (-125 6275);
FORCEPROP 1 LAST TOLERANCE 5%
J 0
(-75 6225);
DISPLAY 0.404255 (-75 6225);
DISPLAY INVISIBLE (-75 6225);
FORCEPROP 1 LAST WATTAGE 1/16W
J 2
(50 6275);
DISPLAY 0.319149 (50 6275);
DISPLAY INVISIBLE (50 6275);
FORCEPROP 1 LAST PATH I15
J 0
(-300 6375);
DISPLAY 0.978723 (-300 6375);
PAINT WHITE (-300 6375);
DISPLAY INVISIBLE (-300 6375);
FORCEPROP 0 LAST CDS_LOCATION R4629
J 0
(-300 6325);
DISPLAY 1.021277 (-300 6325);
DISPLAY INVISIBLE (-300 6325);
FORCEPROP 0 LAST $SEC 1
J 0
(-300 6325);
DISPLAY 0.680851 (-300 6325);
PAINT MONO (-300 6325);
DISPLAY INVISIBLE (-300 6325);
FORCEPROP 0 LAST CDS_SEC 1
J 0
(-300 6325);
DISPLAY 1.021277 (-300 6325);
DISPLAY INVISIBLE (-300 6325);
FORCEADD Q_RES..1
(-250 6375);
FORCEPROP 1 LAST PART_NUMBER CS00002JB13
J 0
(-125 6400);
DISPLAY 0.319149 (-125 6400);
DISPLAY INVISIBLE (-125 6400);
FORCEPROP 1 LAST VALUE 0
J 2
(-100 6375);
DISPLAY 0.404255 (-100 6375);
FORCEPROP 1 LAST MATERIAL CHIP
J 0
(-75 6375);
DISPLAY 0.404255 (-75 6375);
FORCEPROP 1 LAST $LOCATION R4628
J 0
(-550 6375);
DISPLAY 0.978723 (-550 6375);
FORCEPROP 1 LASTPIN (-350 6375) $PN 1
J 0
(-338 6387);
DISPLAY 0.787234 (-338 6387);
PAINT MONO (-338 6387);
FORCEPROP 1 LASTPIN (-150 6375) $PN 2
J 0
(-188 6387);
DISPLAY 0.787234 (-188 6387);
PAINT MONO (-188 6387);
FORCEPROP 2 LAST CDS_LIB pure_quanta
J 0
(-250 6375);
DISPLAY INVISIBLE (-250 6375);
FORCEPROP 1 LAST PACK_TYPE 0402LF
J 0
(-125 6425);
DISPLAY 0.319149 (-125 6425);
DISPLAY INVISIBLE (-125 6425);
FORCEPROP 1 LAST TOLERANCE 5%
J 0
(-75 6375);
DISPLAY 0.404255 (-75 6375);
DISPLAY INVISIBLE (-75 6375);
FORCEPROP 1 LAST WATTAGE 1/16W
J 2
(50 6425);
DISPLAY 0.319149 (50 6425);
DISPLAY INVISIBLE (50 6425);
FORCEPROP 1 LAST PATH I16
J 0
(-300 6525);
DISPLAY 0.978723 (-300 6525);
PAINT WHITE (-300 6525);
DISPLAY INVISIBLE (-300 6525);
FORCEPROP 0 LAST CDS_LOCATION R4628
J 0
(-300 6475);
DISPLAY 1.021277 (-300 6475);
DISPLAY INVISIBLE (-300 6475);
FORCEPROP 0 LAST $SEC 1
J 0
(-300 6475);
DISPLAY 0.680851 (-300 6475);
PAINT MONO (-300 6475);
DISPLAY INVISIBLE (-300 6475);
FORCEPROP 0 LAST CDS_SEC 1
J 0
(-300 6475);
DISPLAY 1.021277 (-300 6475);
DISPLAY INVISIBLE (-300 6475);
FORCEADD Q_RES..1
(-250 6525);
FORCEPROP 1 LAST PART_NUMBER CS00002JB13
J 0
(-125 6550);
DISPLAY 0.319149 (-125 6550);
DISPLAY INVISIBLE (-125 6550);
FORCEPROP 1 LAST MATERIAL CHIP
J 0
(-75 6525);
DISPLAY 0.404255 (-75 6525);
FORCEPROP 1 LAST VALUE 0
J 2
(-100 6525);
DISPLAY 0.404255 (-100 6525);
FORCEPROP 1 LAST $LOCATION R4627
J 0
(-550 6525);
DISPLAY 0.978723 (-550 6525);
FORCEPROP 1 LASTPIN (-350 6525) $PN 1
J 0
(-338 6537);
DISPLAY 0.787234 (-338 6537);
PAINT MONO (-338 6537);
FORCEPROP 1 LASTPIN (-150 6525) $PN 2
J 0
(-188 6537);
DISPLAY 0.787234 (-188 6537);
PAINT MONO (-188 6537);
FORCEPROP 2 LAST CDS_LIB pure_quanta
J 0
(-250 6525);
DISPLAY INVISIBLE (-250 6525);
FORCEPROP 1 LAST WATTAGE 1/16W
J 2
(50 6575);
DISPLAY 0.319149 (50 6575);
DISPLAY INVISIBLE (50 6575);
FORCEPROP 1 LAST TOLERANCE 5%
J 0
(-75 6525);
DISPLAY 0.404255 (-75 6525);
DISPLAY INVISIBLE (-75 6525);
FORCEPROP 1 LAST PACK_TYPE 0402LF
J 0
(-125 6575);
DISPLAY 0.319149 (-125 6575);
DISPLAY INVISIBLE (-125 6575);
FORCEPROP 1 LAST PATH I17
J 0
(-300 6675);
DISPLAY 0.978723 (-300 6675);
PAINT WHITE (-300 6675);
DISPLAY INVISIBLE (-300 6675);
FORCEPROP 0 LAST CDS_LOCATION R4627
J 0
(-300 6625);
DISPLAY 1.021277 (-300 6625);
DISPLAY INVISIBLE (-300 6625);
FORCEPROP 0 LAST $SEC 1
J 0
(-300 6625);
DISPLAY 0.680851 (-300 6625);
PAINT MONO (-300 6625);
DISPLAY INVISIBLE (-300 6625);
FORCEPROP 0 LAST CDS_SEC 1
J 0
(-300 6625);
DISPLAY 1.021277 (-300 6625);
DISPLAY INVISIBLE (-300 6625);
FORCEADD Q_RES..1
(-250 6675);
FORCEPROP 1 LAST PART_NUMBER CS00002JB13
J 0
(-125 6700);
DISPLAY 0.319149 (-125 6700);
DISPLAY INVISIBLE (-125 6700);
FORCEPROP 1 LAST MATERIAL CHIP
J 0
(-75 6675);
DISPLAY 0.404255 (-75 6675);
FORCEPROP 1 LAST VALUE 0
J 2
(-100 6675);
DISPLAY 0.404255 (-100 6675);
FORCEPROP 1 LAST $LOCATION R4626
J 0
(-550 6675);
DISPLAY 0.978723 (-550 6675);
FORCEPROP 1 LASTPIN (-350 6675) $PN 1
J 0
(-338 6687);
DISPLAY 0.787234 (-338 6687);
PAINT MONO (-338 6687);
FORCEPROP 1 LASTPIN (-150 6675) $PN 2
J 0
(-188 6687);
DISPLAY 0.787234 (-188 6687);
PAINT MONO (-188 6687);
FORCEPROP 1 LAST WATTAGE 1/16W
J 2
(50 6725);
DISPLAY 0.319149 (50 6725);
DISPLAY INVISIBLE (50 6725);
FORCEPROP 1 LAST TOLERANCE 5%
J 0
(-75 6675);
DISPLAY 0.404255 (-75 6675);
DISPLAY INVISIBLE (-75 6675);
FORCEPROP 1 LAST PACK_TYPE 0402LF
J 0
(-125 6725);
DISPLAY 0.319149 (-125 6725);
DISPLAY INVISIBLE (-125 6725);
FORCEPROP 2 LAST CDS_LIB pure_quanta
J 0
(-250 6675);
DISPLAY INVISIBLE (-250 6675);
FORCEPROP 1 LAST PATH I18
J 0
(-300 6825);
DISPLAY 0.978723 (-300 6825);
PAINT WHITE (-300 6825);
DISPLAY INVISIBLE (-300 6825);
FORCEPROP 0 LAST CDS_LOCATION R4626
J 0
(-300 6775);
DISPLAY 1.021277 (-300 6775);
DISPLAY INVISIBLE (-300 6775);
FORCEPROP 0 LAST $SEC 1
J 0
(-300 6775);
DISPLAY 0.680851 (-300 6775);
PAINT MONO (-300 6775);
DISPLAY INVISIBLE (-300 6775);
FORCEPROP 0 LAST CDS_SEC 1
J 0
(-300 6775);
DISPLAY 1.021277 (-300 6775);
DISPLAY INVISIBLE (-300 6775);
FORCEADD 74CBTLV3126PW..1
(1575 6475);
FORCEPROP 1 LAST PART_NUMBER AL003126K08
J 0
(1327 6883);
DISPLAY 0.723404 (1327 6883);
PAINT GREEN (1327 6883);
DISPLAY INVISIBLE (1327 6883);
FORCEPROP 1 LAST MATERIAL IC
J 0
(1327 6828);
DISPLAY 0.723404 (1327 6828);
PAINT GREEN (1327 6828);
FORCEPROP 2 LAST VALUE 74CBTLV3126PW
J 0
(1350 6975);
DISPLAY 1.021277 (1350 6975);
FORCEPROP 2 LAST PART_TYPE SMLF
J 0
(1350 7025);
DISPLAY 1.021277 (1350 7025);
FORCEPROP 1 LAST $LOCATION U327
J 0
(1327 6933);
DISPLAY 0.723404 (1327 6933);
PAINT GREEN (1327 6933);
FORCEPROP 0 LASTPIN (1175 6225) $PN 2
J 2
(1165 6235);
DISPLAY 0.680851 (1165 6235);
PAINT MONO (1165 6235);
FORCEPROP 0 LASTPIN (1975 6225) $PN 3
J 0
(1985 6235);
DISPLAY 0.680851 (1985 6235);
PAINT MONO (1985 6235);
FORCEPROP 0 LASTPIN (1175 6175) $PN 1
J 2
(1165 6185);
DISPLAY 0.680851 (1165 6185);
PAINT MONO (1165 6185);
FORCEPROP 0 LASTPIN (1175 6375) $PN 5
J 2
(1165 6385);
DISPLAY 0.680851 (1165 6385);
PAINT MONO (1165 6385);
FORCEPROP 0 LASTPIN (1975 6375) $PN 6
J 0
(1985 6385);
DISPLAY 0.680851 (1985 6385);
PAINT MONO (1985 6385);
FORCEPROP 0 LASTPIN (1175 6325) $PN 4
J 2
(1165 6335);
DISPLAY 0.680851 (1165 6335);
PAINT MONO (1165 6335);
FORCEPROP 0 LASTPIN (1175 6525) $PN 9
J 2
(1165 6535);
DISPLAY 0.680851 (1165 6535);
PAINT MONO (1165 6535);
FORCEPROP 0 LASTPIN (1975 6525) $PN 8
J 0
(1985 6535);
DISPLAY 0.680851 (1985 6535);
PAINT MONO (1985 6535);
FORCEPROP 0 LASTPIN (1175 6475) $PN 10
J 2
(1165 6485);
DISPLAY 0.680851 (1165 6485);
PAINT MONO (1165 6485);
FORCEPROP 0 LASTPIN (1175 6675) $PN 12
J 2
(1165 6685);
DISPLAY 0.680851 (1165 6685);
PAINT MONO (1165 6685);
FORCEPROP 0 LASTPIN (1975 6675) $PN 11
J 0
(1985 6685);
DISPLAY 0.680851 (1985 6685);
PAINT MONO (1985 6685);
FORCEPROP 0 LASTPIN (1175 6625) $PN 13
J 2
(1165 6635);
DISPLAY 0.680851 (1165 6635);
PAINT MONO (1165 6635);
FORCEPROP 0 LASTPIN (1975 6175) $PN 7
J 0
(1985 6185);
DISPLAY 0.680851 (1985 6185);
PAINT MONO (1985 6185);
FORCEPROP 0 LASTPIN (1975 6725) $PN 14
J 0
(1985 6735);
DISPLAY 0.680851 (1985 6735);
PAINT MONO (1985 6735);
FORCEPROP 1 LAST CDS_LMAN_SYM_OUTLINE -250,350,250,-350
J 0
(1575 6475);
DISPLAY 0.468085 (1575 6475);
PAINT GREEN (1575 6475);
DISPLAY INVISIBLE (1575 6475);
FORCEPROP 1 LAST NEEDS_NO_SIZE TRUE
J 0
(1825 6165);
DISPLAY 0.723404 (1825 6165);
PAINT GREEN (1825 6165);
DISPLAY INVISIBLE (1825 6165);
FORCEPROP 2 LAST CDS_LIB pure_quanta
J 0
(1575 6475);
DISPLAY INVISIBLE (1575 6475);
FORCEPROP 1 LAST PATH I19
J 0
(1825 6125);
DISPLAY 0.723404 (1825 6125);
PAINT GREEN (1825 6125);
DISPLAY INVISIBLE (1825 6125);
FORCEPROP 0 LAST CDS_LOCATION U327
J 0
(1350 7075);
DISPLAY 1.021277 (1350 7075);
DISPLAY INVISIBLE (1350 7075);
FORCEPROP 0 LAST $SEC 1
J 0
(1350 7075);
DISPLAY 0.680851 (1350 7075);
PAINT MONO (1350 7075);
DISPLAY INVISIBLE (1350 7075);
FORCEPROP 0 LAST CDS_SEC 1
J 0
(1350 7075);
DISPLAY 1.021277 (1350 7075);
DISPLAY INVISIBLE (1350 7075);
FORCEADD OFFPAGE..1
(-3075 5775);
FORCEPROP 2 LAST $XR0 213 
J 0
(-3327 5775);
DISPLAY 0.638298 (-3327 5775);
PAINT MONO (-3327 5775);
FORCEPROP 2 LAST CDS_LIB standard
J 0
(-3075 5775);
DISPLAY INVISIBLE (-3075 5775);
FORCEPROP 1 LAST COMMENT_BODY TRUE
J 0
(-2950 5675);
DISPLAY 0.872340 (-2950 5675);
PAINT GREEN (-2950 5675);
DISPLAY INVISIBLE (-2950 5675);
FORCEPROP 1 LAST OFFPAGE TRUE
J 0
(-2750 5650);
DISPLAY 0.872340 (-2750 5650);
PAINT GREEN (-2750 5650);
DISPLAY INVISIBLE (-2750 5650);
FORCEPROP 2 LAST PATH I2
J 0
(-3325 5825);
DISPLAY 1.021277 (-3325 5825);
DISPLAY INVISIBLE (-3325 5825);
FORCEADD UNIVERSAL_GND..1
(2100 6000);
FORCEPROP 3 LASTPIN (2100 6050) SIG_NAME GND\g
J 0
(2110 6060);
DISPLAY 0.659574 (2110 6060);
PAINT MONO (2110 6060);
DISPLAY INVISIBLE (2110 6060);
FORCEPROP 1 LAST HDL_POWER GND
J 1
(2125 5925);
DISPLAY 0.872340 (2125 5925);
PAINT GREEN (2125 5925);
DISPLAY INVISIBLE (2125 5925);
FORCEPROP 2 LAST CDS_LIB logical_power
J 0
(2100 6000);
PAINT MONO (2100 6000);
DISPLAY INVISIBLE (2100 6000);
FORCEPROP 1 LAST PATH I20
J 0
(2175 6000);
DISPLAY 0.872340 (2175 6000);
PAINT AQUA (2175 6000);
DISPLAY INVISIBLE (2175 6000);
FORCEADD UNIVERSAL_POWER..1
(2075 7350);
FORCEPROP 3 LASTPIN (2075 7300) SIG_NAME P3V3_AUX\g
J 0
(2085 7310);
DISPLAY 0.659574 (2085 7310);
PAINT MONO (2085 7310);
DISPLAY INVISIBLE (2085 7310);
FORCEPROP 1 LAST HDL_POWER P3V3_AUX
J 1
(2075 7400);
DISPLAY 0.872340 (2075 7400);
PAINT GREEN (2075 7400);
FORCEPROP 2 LAST CDS_LIB logical_power
J 0
(2075 7350);
PAINT MONO (2075 7350);
DISPLAY INVISIBLE (2075 7350);
FORCEPROP 1 LAST PATH I21
J 0
(2125 7375);
DISPLAY 0.872340 (2125 7375);
PAINT AQUA (2125 7375);
DISPLAY INVISIBLE (2125 7375);
FORCEADD UNIVERSAL_GND..1
(2225 6875);
FORCEPROP 3 LASTPIN (2225 6925) SIG_NAME GND\g
J 0
(2235 6935);
DISPLAY 0.659574 (2235 6935);
PAINT MONO (2235 6935);
DISPLAY INVISIBLE (2235 6935);
FORCEPROP 2 LAST CDS_LIB logical_power
J 0
(2225 6875);
PAINT MONO (2225 6875);
DISPLAY INVISIBLE (2225 6875);
FORCEPROP 1 LAST HDL_POWER GND
J 1
(2250 6800);
DISPLAY 0.872340 (2250 6800);
PAINT GREEN (2250 6800);
DISPLAY INVISIBLE (2250 6800);
FORCEPROP 1 LAST PATH I22
J 0
(2300 6875);
DISPLAY 0.872340 (2300 6875);
PAINT AQUA (2300 6875);
DISPLAY INVISIBLE (2300 6875);
FORCEADD Q_CAP..1
(2225 7075);
FORCEPROP 1 LAST PART_NUMBER CH4104K1B00
J 0
(2275 6925);
DISPLAY 0.510638 (2275 6925);
DISPLAY INVISIBLE (2275 6925);
FORCEPROP 1 LAST VALUE 0.1UF
J 0
(2275 7125);
DISPLAY 0.510638 (2275 7125);
FORCEPROP 1 LAST VOLTAGE 25V
J 0
(2275 7075);
DISPLAY 0.510638 (2275 7075);
FORCEPROP 1 LAST MATERIAL X7R
J 0
(2275 6975);
DISPLAY 0.510638 (2275 6975);
FORCEPROP 1 LAST TOLERANCE 10%
J 0
(2275 7025);
DISPLAY 0.510638 (2275 7025);
FORCEPROP 1 LAST PACK_TYPE 0402
J 0
(2275 6875);
DISPLAY 0.510638 (2275 6875);
FORCEPROP 1 LAST $LOCATION C2348
J 0
(2275 7175);
DISPLAY 0.787234 (2275 7175);
FORCEPROP 1 LASTPIN (2225 7175) $PN 1
J 0
(2235 7155);
DISPLAY 0.787234 (2235 7155);
FORCEPROP 1 LASTPIN (2225 6975) $PN 2
J 0
(2235 6955);
DISPLAY 0.787234 (2235 6955);
FORCEPROP 2 LAST CDS_LIB pure_quanta
J 2
(2225 7075);
PAINT MONO (2225 7075);
DISPLAY INVISIBLE (2225 7075);
FORCEPROP 1 LAST PATH I23
J 0
(2275 7225);
DISPLAY 0.978723 (2275 7225);
PAINT WHITE (2275 7225);
DISPLAY INVISIBLE (2275 7225);
FORCEPROP 2 LAST CDS_LOCATION C2348
J 0
(2275 7275);
DISPLAY 1.021277 (2275 7275);
DISPLAY INVISIBLE (2275 7275);
FORCEPROP 2 LAST $SEC 1
J 0
(2275 7275);
DISPLAY 0.680851 (2275 7275);
PAINT MONO (2275 7275);
DISPLAY INVISIBLE (2275 7275);
FORCEPROP 2 LAST CDS_SEC 1
J 0
(2275 7275);
DISPLAY 1.021277 (2275 7275);
DISPLAY INVISIBLE (2275 7275);
FORCEADD Q_RES..1
(3400 6225);
FORCEPROP 1 LAST PART_NUMBER CS00002JB13
J 0
(3525 6250);
DISPLAY 0.319149 (3525 6250);
DISPLAY INVISIBLE (3525 6250);
FORCEPROP 1 LAST MATERIAL CHIP
J 0
(3575 6225);
DISPLAY 0.404255 (3575 6225);
FORCEPROP 1 LAST VALUE 0
J 2
(3550 6225);
DISPLAY 0.404255 (3550 6225);
FORCEPROP 1 LAST $LOCATION R4633
J 0
(3100 6225);
DISPLAY 0.978723 (3100 6225);
FORCEPROP 1 LASTPIN (3300 6225) $PN 1
J 0
(3312 6237);
DISPLAY 0.787234 (3312 6237);
PAINT MONO (3312 6237);
FORCEPROP 1 LASTPIN (3500 6225) $PN 2
J 0
(3462 6237);
DISPLAY 0.787234 (3462 6237);
PAINT MONO (3462 6237);
FORCEPROP 2 LAST CDS_LIB pure_quanta
J 0
(3400 6225);
DISPLAY INVISIBLE (3400 6225);
FORCEPROP 1 LAST WATTAGE 1/16W
J 2
(3700 6275);
DISPLAY 0.319149 (3700 6275);
DISPLAY INVISIBLE (3700 6275);
FORCEPROP 1 LAST TOLERANCE 5%
J 0
(3575 6225);
DISPLAY 0.404255 (3575 6225);
DISPLAY INVISIBLE (3575 6225);
FORCEPROP 1 LAST PACK_TYPE 0402LF
J 0
(3525 6275);
DISPLAY 0.319149 (3525 6275);
DISPLAY INVISIBLE (3525 6275);
FORCEPROP 1 LAST PATH I24
J 0
(3350 6375);
DISPLAY 0.978723 (3350 6375);
PAINT WHITE (3350 6375);
DISPLAY INVISIBLE (3350 6375);
FORCEPROP 0 LAST CDS_LOCATION R4633
J 0
(3350 6325);
DISPLAY 1.021277 (3350 6325);
DISPLAY INVISIBLE (3350 6325);
FORCEPROP 0 LAST $SEC 1
J 0
(3350 6325);
DISPLAY 0.680851 (3350 6325);
PAINT MONO (3350 6325);
DISPLAY INVISIBLE (3350 6325);
FORCEPROP 0 LAST CDS_SEC 1
J 0
(3350 6325);
DISPLAY 1.021277 (3350 6325);
DISPLAY INVISIBLE (3350 6325);
FORCEADD Q_RES..1
(3400 6525);
FORCEPROP 1 LAST PART_NUMBER CS00002JB13
J 0
(3525 6550);
DISPLAY 0.319149 (3525 6550);
DISPLAY INVISIBLE (3525 6550);
FORCEPROP 1 LAST VALUE 0
J 2
(3550 6525);
DISPLAY 0.404255 (3550 6525);
FORCEPROP 1 LAST MATERIAL CHIP
J 0
(3575 6525);
DISPLAY 0.404255 (3575 6525);
FORCEPROP 1 LAST $LOCATION R4631
J 0
(3100 6525);
DISPLAY 0.978723 (3100 6525);
FORCEPROP 1 LASTPIN (3300 6525) $PN 1
J 0
(3312 6537);
DISPLAY 0.787234 (3312 6537);
PAINT MONO (3312 6537);
FORCEPROP 1 LASTPIN (3500 6525) $PN 2
J 0
(3462 6537);
DISPLAY 0.787234 (3462 6537);
PAINT MONO (3462 6537);
FORCEPROP 2 LAST CDS_LIB pure_quanta
J 0
(3400 6525);
DISPLAY INVISIBLE (3400 6525);
FORCEPROP 1 LAST PACK_TYPE 0402LF
J 0
(3525 6575);
DISPLAY 0.319149 (3525 6575);
DISPLAY INVISIBLE (3525 6575);
FORCEPROP 1 LAST TOLERANCE 5%
J 0
(3575 6525);
DISPLAY 0.404255 (3575 6525);
DISPLAY INVISIBLE (3575 6525);
FORCEPROP 1 LAST WATTAGE 1/16W
J 2
(3700 6575);
DISPLAY 0.319149 (3700 6575);
DISPLAY INVISIBLE (3700 6575);
FORCEPROP 1 LAST PATH I25
J 0
(3350 6675);
DISPLAY 0.978723 (3350 6675);
PAINT WHITE (3350 6675);
DISPLAY INVISIBLE (3350 6675);
FORCEPROP 0 LAST CDS_LOCATION R4631
J 0
(3350 6625);
DISPLAY 1.021277 (3350 6625);
DISPLAY INVISIBLE (3350 6625);
FORCEPROP 0 LAST $SEC 1
J 0
(3350 6625);
DISPLAY 0.680851 (3350 6625);
PAINT MONO (3350 6625);
DISPLAY INVISIBLE (3350 6625);
FORCEPROP 0 LAST CDS_SEC 1
J 0
(3350 6625);
DISPLAY 1.021277 (3350 6625);
DISPLAY INVISIBLE (3350 6625);
FORCEADD Q_RES..1
(3400 6375);
FORCEPROP 1 LAST PART_NUMBER CS00002JB13
J 0
(3525 6400);
DISPLAY 0.319149 (3525 6400);
DISPLAY INVISIBLE (3525 6400);
FORCEPROP 1 LAST MATERIAL CHIP
J 0
(3575 6375);
DISPLAY 0.404255 (3575 6375);
FORCEPROP 1 LAST VALUE 0
J 2
(3550 6375);
DISPLAY 0.404255 (3550 6375);
FORCEPROP 1 LAST $LOCATION R4632
J 0
(3100 6375);
DISPLAY 0.978723 (3100 6375);
FORCEPROP 1 LASTPIN (3300 6375) $PN 1
J 0
(3312 6387);
DISPLAY 0.787234 (3312 6387);
PAINT MONO (3312 6387);
FORCEPROP 1 LASTPIN (3500 6375) $PN 2
J 0
(3462 6387);
DISPLAY 0.787234 (3462 6387);
PAINT MONO (3462 6387);
FORCEPROP 2 LAST CDS_LIB pure_quanta
J 0
(3400 6375);
DISPLAY INVISIBLE (3400 6375);
FORCEPROP 1 LAST WATTAGE 1/16W
J 2
(3700 6425);
DISPLAY 0.319149 (3700 6425);
DISPLAY INVISIBLE (3700 6425);
FORCEPROP 1 LAST TOLERANCE 5%
J 0
(3575 6375);
DISPLAY 0.404255 (3575 6375);
DISPLAY INVISIBLE (3575 6375);
FORCEPROP 1 LAST PACK_TYPE 0402LF
J 0
(3525 6425);
DISPLAY 0.319149 (3525 6425);
DISPLAY INVISIBLE (3525 6425);
FORCEPROP 1 LAST PATH I26
J 0
(3350 6525);
DISPLAY 0.978723 (3350 6525);
PAINT WHITE (3350 6525);
DISPLAY INVISIBLE (3350 6525);
FORCEPROP 0 LAST CDS_LOCATION R4632
J 0
(3350 6475);
DISPLAY 1.021277 (3350 6475);
DISPLAY INVISIBLE (3350 6475);
FORCEPROP 0 LAST $SEC 1
J 0
(3350 6475);
DISPLAY 0.680851 (3350 6475);
PAINT MONO (3350 6475);
DISPLAY INVISIBLE (3350 6475);
FORCEPROP 0 LAST CDS_SEC 1
J 0
(3350 6475);
DISPLAY 1.021277 (3350 6475);
DISPLAY INVISIBLE (3350 6475);
FORCEADD Q_RES..1
(3400 6675);
FORCEPROP 1 LAST PART_NUMBER CS00002JB13
J 0
(3525 6700);
DISPLAY 0.319149 (3525 6700);
DISPLAY INVISIBLE (3525 6700);
FORCEPROP 1 LAST VALUE 0
J 2
(3550 6675);
DISPLAY 0.404255 (3550 6675);
FORCEPROP 1 LAST MATERIAL CHIP
J 0
(3575 6675);
DISPLAY 0.404255 (3575 6675);
FORCEPROP 1 LAST $LOCATION R4630
J 0
(3100 6675);
DISPLAY 0.978723 (3100 6675);
FORCEPROP 1 LASTPIN (3300 6675) $PN 1
J 0
(3312 6687);
DISPLAY 0.787234 (3312 6687);
PAINT MONO (3312 6687);
FORCEPROP 1 LASTPIN (3500 6675) $PN 2
J 0
(3462 6687);
DISPLAY 0.787234 (3462 6687);
PAINT MONO (3462 6687);
FORCEPROP 2 LAST CDS_LIB pure_quanta
J 0
(3400 6675);
DISPLAY INVISIBLE (3400 6675);
FORCEPROP 1 LAST PACK_TYPE 0402LF
J 0
(3525 6725);
DISPLAY 0.319149 (3525 6725);
DISPLAY INVISIBLE (3525 6725);
FORCEPROP 1 LAST TOLERANCE 5%
J 0
(3575 6675);
DISPLAY 0.404255 (3575 6675);
DISPLAY INVISIBLE (3575 6675);
FORCEPROP 1 LAST WATTAGE 1/16W
J 2
(3700 6725);
DISPLAY 0.319149 (3700 6725);
DISPLAY INVISIBLE (3700 6725);
FORCEPROP 1 LAST PATH I27
J 0
(3350 6825);
DISPLAY 0.978723 (3350 6825);
PAINT WHITE (3350 6825);
DISPLAY INVISIBLE (3350 6825);
FORCEPROP 0 LAST CDS_LOCATION R4630
J 0
(3350 6775);
DISPLAY 1.021277 (3350 6775);
DISPLAY INVISIBLE (3350 6775);
FORCEPROP 0 LAST $SEC 1
J 0
(3350 6775);
DISPLAY 0.680851 (3350 6775);
PAINT MONO (3350 6775);
DISPLAY INVISIBLE (3350 6775);
FORCEPROP 0 LAST CDS_SEC 1
J 0
(3350 6775);
DISPLAY 1.021277 (3350 6775);
DISPLAY INVISIBLE (3350 6775);
FORCEADD OFFPAGE..2
(4875 6225);
FORCEPROP 2 LAST $XR0 239 
J 0
(5064 6225);
DISPLAY 0.638298 (5064 6225);
PAINT MONO (5064 6225);
FORCEPROP 2 LAST CDS_LIB standard
J 0
(4875 6225);
DISPLAY INVISIBLE (4875 6225);
FORCEPROP 1 LAST COMMENT_BODY TRUE
J 0
(4830 6130);
DISPLAY 0.872340 (4830 6130);
PAINT GREEN (4830 6130);
DISPLAY INVISIBLE (4830 6130);
FORCEPROP 1 LAST OFFPAGE TRUE
J 0
(5200 6100);
DISPLAY 0.872340 (5200 6100);
DISPLAY INVISIBLE (5200 6100);
FORCEPROP 2 LAST PATH I28
J 0
(5075 6275);
DISPLAY 1.021277 (5075 6275);
DISPLAY INVISIBLE (5075 6275);
FORCEADD OFFPAGE..2
(4875 6375);
FORCEPROP 2 LAST $XR0 239 
J 0
(5064 6375);
DISPLAY 0.638298 (5064 6375);
PAINT MONO (5064 6375);
FORCEPROP 2 LAST CDS_LIB standard
J 0
(4875 6375);
DISPLAY INVISIBLE (4875 6375);
FORCEPROP 1 LAST OFFPAGE TRUE
J 0
(5200 6250);
DISPLAY 0.872340 (5200 6250);
DISPLAY INVISIBLE (5200 6250);
FORCEPROP 1 LAST COMMENT_BODY TRUE
J 0
(4830 6280);
DISPLAY 0.872340 (4830 6280);
PAINT GREEN (4830 6280);
DISPLAY INVISIBLE (4830 6280);
FORCEPROP 2 LAST PATH I29
J 0
(5075 6425);
DISPLAY 1.021277 (5075 6425);
DISPLAY INVISIBLE (5075 6425);
FORCEADD Q_RES..2
(-2225 5475);
FORCEPROP 1 LAST PART_NUMBER CS31002FB08
J 0
(-2185 5300);
DISPLAY 0.510638 (-2185 5300);
DISPLAY INVISIBLE (-2185 5300);
FORCEPROP 1 LAST MATERIAL CHIP
J 0
(-2185 5400);
DISPLAY 0.510638 (-2185 5400);
FORCEPROP 1 LAST PACK_TYPE 0402LF
J 0
(-2185 5350);
DISPLAY 0.510638 (-2185 5350);
FORCEPROP 1 LAST VALUE 10K
J 0
(-2180 5550);
DISPLAY 0.510638 (-2180 5550);
FORCEPROP 1 LAST TOLERANCE 1%
J 0
(-2180 5500);
DISPLAY 0.510638 (-2180 5500);
FORCEPROP 1 LAST WATTAGE 1/16W
J 0
(-2185 5450);
DISPLAY 0.510638 (-2185 5450);
FORCEPROP 1 LAST $LOCATION R4635
J 0
(-2180 5600);
DISPLAY 0.978723 (-2180 5600);
FORCEPROP 1 LASTPIN (-2225 5575) $PN 1
J 0
(-2220 5537);
DISPLAY 0.787234 (-2220 5537);
PAINT MONO (-2220 5537);
FORCEPROP 1 LASTPIN (-2225 5375) $PN 2
J 0
(-2220 5385);
DISPLAY 0.787234 (-2220 5385);
PAINT MONO (-2220 5385);
FORCEPROP 2 LAST CDS_LIB pure_quanta
J 0
(-2225 5475);
DISPLAY INVISIBLE (-2225 5475);
FORCEPROP 1 LAST PATH I3
J 0
(-2175 5650);
DISPLAY 0.978723 (-2175 5650);
PAINT WHITE (-2175 5650);
DISPLAY INVISIBLE (-2175 5650);
FORCEPROP 0 LAST CDS_LOCATION R4635
J 0
(-2175 5650);
DISPLAY 1.021277 (-2175 5650);
DISPLAY INVISIBLE (-2175 5650);
FORCEPROP 0 LAST $SEC 1
J 0
(-2175 5650);
DISPLAY 0.680851 (-2175 5650);
PAINT MONO (-2175 5650);
DISPLAY INVISIBLE (-2175 5650);
FORCEPROP 0 LAST CDS_SEC 1
J 0
(-2175 5650);
DISPLAY 1.021277 (-2175 5650);
DISPLAY INVISIBLE (-2175 5650);
FORCEADD OFFPAGE..2
(4875 6525);
FORCEPROP 2 LAST $XR0 239 
J 0
(5064 6525);
DISPLAY 0.638298 (5064 6525);
PAINT MONO (5064 6525);
FORCEPROP 1 LAST COMMENT_BODY TRUE
J 0
(4830 6430);
DISPLAY 0.872340 (4830 6430);
PAINT GREEN (4830 6430);
DISPLAY INVISIBLE (4830 6430);
FORCEPROP 1 LAST OFFPAGE TRUE
J 0
(5200 6400);
DISPLAY 0.872340 (5200 6400);
DISPLAY INVISIBLE (5200 6400);
FORCEPROP 2 LAST CDS_LIB standard
J 0
(4875 6525);
DISPLAY INVISIBLE (4875 6525);
FORCEPROP 2 LAST PATH I30
J 0
(5075 6575);
DISPLAY 1.021277 (5075 6575);
DISPLAY INVISIBLE (5075 6575);
FORCEADD OFFPAGE..1
R 2
(4875 6675);
FORCEPROP 2 LAST $XR0 239 
J 0
(5061 6675);
DISPLAY 0.638298 (5061 6675);
PAINT MONO (5061 6675);
FORCEPROP 2 LAST CDS_LIB standard
J 2
(4875 6675);
DISPLAY INVISIBLE (4875 6675);
FORCEPROP 1 LAST COMMENT_BODY TRUE
J 2
(4750 6575);
DISPLAY 0.872340 (4750 6575);
PAINT GREEN (4750 6575);
DISPLAY INVISIBLE (4750 6575);
FORCEPROP 1 LAST OFFPAGE TRUE
J 2
(4550 6550);
DISPLAY 0.872340 (4550 6550);
PAINT GREEN (4550 6550);
DISPLAY INVISIBLE (4550 6550);
FORCEPROP 2 LAST PATH I31
J 0
(5075 6725);
DISPLAY 1.021277 (5075 6725);
DISPLAY INVISIBLE (5075 6725);
FORCEADD Q_RES..2
(-2250 6000);
FORCEPROP 1 LAST PART_NUMBER CS21002FB06
J 0
(-2210 5875);
DISPLAY 0.978723 (-2210 5875);
DISPLAY INVISIBLE (-2210 5875);
FORCEPROP 1 LAST TOLERANCE 1%
J 0
(-2205 6025);
DISPLAY 0.978723 (-2205 6025);
FORCEPROP 1 LAST PACK_TYPE 0402LF
J 0
(-2210 5825);
DISPLAY 0.978723 (-2210 5825);
FORCEPROP 1 LAST VALUE 1K
J 0
(-2205 6075);
DISPLAY 0.978723 (-2205 6075);
FORCEPROP 1 LAST MATERIAL EMPTY
J 0
(-2210 5925);
DISPLAY 0.978723 (-2210 5925);
PAINT RED (-2210 5925);
FORCEPROP 1 LAST WATTAGE 1/16W
J 0
(-2210 5975);
DISPLAY 0.978723 (-2210 5975);
FORCEPROP 1 LAST $LOCATION R4634
J 0
(-2205 6125);
DISPLAY 0.978723 (-2205 6125);
FORCEPROP 1 LASTPIN (-2250 6100) $PN 1
J 0
(-2245 6062);
DISPLAY 0.787234 (-2245 6062);
PAINT MONO (-2245 6062);
FORCEPROP 1 LASTPIN (-2250 5900) $PN 2
J 0
(-2245 5910);
DISPLAY 0.787234 (-2245 5910);
PAINT MONO (-2245 5910);
FORCEPROP 2 LAST CDS_LIB pure_quanta
J 0
(-2250 6000);
PAINT MONO (-2250 6000);
DISPLAY INVISIBLE (-2250 6000);
FORCEPROP 1 LAST PATH I4
J 0
(-2200 6175);
DISPLAY 0.978723 (-2200 6175);
PAINT WHITE (-2200 6175);
DISPLAY INVISIBLE (-2200 6175);
FORCEPROP 2 LAST CDS_LOCATION R4634
J 0
(-2300 6200);
DISPLAY 1.021277 (-2300 6200);
DISPLAY INVISIBLE (-2300 6200);
FORCEPROP 0 LAST $SEC 1
J 0
(-2200 6175);
DISPLAY 0.680851 (-2200 6175);
PAINT MONO (-2200 6175);
DISPLAY INVISIBLE (-2200 6175);
FORCEPROP 2 LAST CDS_SEC 1
J 0
(-2300 6200);
DISPLAY 1.021277 (-2300 6200);
DISPLAY INVISIBLE (-2300 6200);
FORCEADD UNIVERSAL_POWER..1
(-2250 6275);
FORCEPROP 3 LASTPIN (-2250 6225) SIG_NAME P3V3_AUX\g
J 0
(-2240 6235);
DISPLAY 0.659574 (-2240 6235);
PAINT MONO (-2240 6235);
DISPLAY INVISIBLE (-2240 6235);
FORCEPROP 1 LAST HDL_POWER P3V3_AUX
J 1
(-2250 6325);
DISPLAY 0.872340 (-2250 6325);
PAINT GREEN (-2250 6325);
FORCEPROP 2 LAST CDS_LIB logical_power
J 0
(-2250 6275);
DISPLAY INVISIBLE (-2250 6275);
FORCEPROP 1 LAST PATH I5
J 0
(-2200 6300);
DISPLAY 0.872340 (-2200 6300);
PAINT AQUA (-2200 6300);
DISPLAY INVISIBLE (-2200 6300);
FORCEADD OFFPAGE..1
(-1725 6225);
FORCEPROP 2 LAST $XR0 240 
J 0
(-1977 6225);
DISPLAY 0.638298 (-1977 6225);
PAINT MONO (-1977 6225);
FORCEPROP 2 LAST CDS_LIB standard
J 0
(-1725 6225);
PAINT MONO (-1725 6225);
DISPLAY INVISIBLE (-1725 6225);
FORCEPROP 1 LAST COMMENT_BODY TRUE
J 0
(-1600 6125);
DISPLAY 0.872340 (-1600 6125);
PAINT GREEN (-1600 6125);
DISPLAY INVISIBLE (-1600 6125);
FORCEPROP 1 LAST OFFPAGE TRUE
J 0
(-1400 6100);
DISPLAY 0.872340 (-1400 6100);
PAINT GREEN (-1400 6100);
DISPLAY INVISIBLE (-1400 6100);
FORCEPROP 2 LAST PATH I6
J 0
(-1975 6275);
DISPLAY 1.021277 (-1975 6275);
DISPLAY INVISIBLE (-1975 6275);
FORCEADD OFFPAGE..1
(-1725 6375);
FORCEPROP 2 LAST $XR0 240 
J 0
(-1977 6375);
DISPLAY 0.638298 (-1977 6375);
PAINT MONO (-1977 6375);
FORCEPROP 1 LAST COMMENT_BODY TRUE
J 0
(-1600 6275);
DISPLAY 0.872340 (-1600 6275);
PAINT GREEN (-1600 6275);
DISPLAY INVISIBLE (-1600 6275);
FORCEPROP 1 LAST OFFPAGE TRUE
J 0
(-1400 6250);
DISPLAY 0.872340 (-1400 6250);
PAINT GREEN (-1400 6250);
DISPLAY INVISIBLE (-1400 6250);
FORCEPROP 2 LAST CDS_LIB standard
J 0
(-1725 6375);
PAINT MONO (-1725 6375);
DISPLAY INVISIBLE (-1725 6375);
FORCEPROP 2 LAST PATH I7
J 0
(-1975 6425);
DISPLAY 1.021277 (-1975 6425);
DISPLAY INVISIBLE (-1975 6425);
FORCEADD OFFPAGE..1
(-1725 6525);
FORCEPROP 2 LAST $XR0 240 
J 0
(-1977 6525);
DISPLAY 0.638298 (-1977 6525);
PAINT MONO (-1977 6525);
FORCEPROP 1 LAST COMMENT_BODY TRUE
J 0
(-1600 6425);
DISPLAY 0.872340 (-1600 6425);
PAINT GREEN (-1600 6425);
DISPLAY INVISIBLE (-1600 6425);
FORCEPROP 1 LAST OFFPAGE TRUE
J 0
(-1400 6400);
DISPLAY 0.872340 (-1400 6400);
PAINT GREEN (-1400 6400);
DISPLAY INVISIBLE (-1400 6400);
FORCEPROP 2 LAST CDS_LIB standard
J 0
(-1725 6525);
PAINT MONO (-1725 6525);
DISPLAY INVISIBLE (-1725 6525);
FORCEPROP 2 LAST PATH I8
J 0
(-1975 6575);
DISPLAY 1.021277 (-1975 6575);
DISPLAY INVISIBLE (-1975 6575);
FORCEADD OFFPAGE..5
(-1725 6675);
FORCEPROP 2 LAST $XR0 240 
J 0
(-1980 6675);
DISPLAY 0.638298 (-1980 6675);
PAINT MONO (-1980 6675);
FORCEPROP 2 LAST CDS_LIB standard
J 0
(-1725 6675);
PAINT MONO (-1725 6675);
DISPLAY INVISIBLE (-1725 6675);
FORCEPROP 1 LAST COMMENT_BODY TRUE
J 0
(-1625 6600);
DISPLAY 0.872340 (-1625 6600);
PAINT PEACH (-1625 6600);
DISPLAY INVISIBLE (-1625 6600);
FORCEPROP 1 LAST OFFPAGE TRUE
J 0
(-1400 6550);
DISPLAY 0.872340 (-1400 6550);
PAINT GREEN (-1400 6550);
DISPLAY INVISIBLE (-1400 6550);
FORCEPROP 2 LAST PATH I9
J 0
(-1975 6725);
DISPLAY 1.021277 (-1975 6725);
DISPLAY INVISIBLE (-1975 6725);
FORCEADD DNS..2
(-2250 5975);
PAINT RED (-2250 5975);
FORCEPROP 1 LAST COMMENT_BODY TRUE
J 0
(-2250 5975);
DISPLAY INVISIBLE (-2250 5975);
FORCEPROP 2 LAST CDS_LIB mstr_misc
J 0
(-2250 5975);
DISPLAY INVISIBLE (-2250 5975);
FORCEADD QUANTA_TITLE_BLOCK_C..1
(5475 1800);
FORCEPROP 0 LAST CDS_CON_LAST_MODIFIED Fri Aug 25 14:04:18 2023
J 0
(3590 1815);
DISPLAY INVISIBLE (3590 1815);
FORCEPROP 2 LAST CUSTOM_TXT_CDS <XR_PAGE_TITLE>
J 0
(-2415 7050);
DISPLAY 0.638298 (-2415 7050);
PAINT PINK (-2415 7050);
DISPLAY INVISIBLE (-2415 7050);
FORCEPROP 2 LAST CUSTOM_TXT_CDS <CON_LAST_MODIFIED>
J 0
(3590 1815);
DISPLAY 0.978723 (3590 1815);
FORCEPROP 2 LAST CUSTOM_TXT_CDS <Q_REV>
J 0
(5291 1903);
DISPLAY 1.212766 (5291 1903);
FORCEPROP 2 LAST CUSTOM_TXT_CDS <NAME_1>
J 0
(2300 1975);
FORCEPROP 2 LAST CUSTOM_TXT_CDS <NAME_2>
J 0
(2300 1850);
FORCEPROP 2 LAST CUSTOM_TXT_CDS <Q_NUMBER>
J 0
(4072 1903);
DISPLAY 1.212766 (4072 1903);
FORCEPROP 2 LAST CUSTOM_TXT_CDS <Q_PROJ>
J 0
(3093 1902);
DISPLAY 1.212766 (3093 1902);
FORCEPROP 2 LAST CUSTOM_TXT_CDS <CON_PAGE_NUM> OF <CON_TOTAL_PAGES>
J 0
(5029 1818);
DISPLAY 0.978723 (5029 1818);
FORCEPROP 1 LAST Q_TITLE SCM REMOTE JTAG LOGIC
J 0
(-3841 1851);
DISPLAY 2.446809 (-3841 1851);
PAINT GREEN (-3841 1851);
FORCEPROP 1 LAST Q_DEPT 
J 1
(1712 1849);
DISPLAY 1.957447 (1712 1849);
PAINT GREEN (1712 1849);
FORCEPROP 2 LAST CDS_XR_PAGE_TITLE CR-248 : @S9S_MB_2U_LIB.S9S_MB_2U(SCH_1):PAGE248
J 0
(-2415 7050);
DISPLAY 0.638298 (-2415 7050);
PAINT PINK (-2415 7050);
DISPLAY INVISIBLE (-2415 7050);
FORCEPROP 2 LAST PAGE_BORDER TRUE
J 0
(-2415 7050);
DISPLAY 0.638298 (-2415 7050);
PAINT PINK (-2415 7050);
DISPLAY INVISIBLE (-2415 7050);
FORCEPROP 1 LAST COMMENT_BODY TRUE
J 0
(5487 1787);
DISPLAY 0.978723 (5487 1787);
PAINT GREEN (5487 1787);
DISPLAY INVISIBLE (5487 1787);
FORCEPROP 1 LAST CDS_LMAN_SYM_OUTLINE -9475,6775,100,-125
J 0
(5475 1800);
DISPLAY 0.468085 (5475 1800);
PAINT GREEN (5475 1800);
DISPLAY INVISIBLE (5475 1800);
FORCEPROP 2 LAST CDS_LIB pure_quanta
J 0
(5475 1800);
DISPLAY INVISIBLE (5475 1800);
WIRE 16 -1 (-2250 6225)(-2250 6100);
WIRE 16 -1 (-750 5000)(-750 4950);
WIRE 16 -1 (2075 7300)(2075 7250);
WIRE 16 -1 (-2225 5375)(-2225 5250);
WIRE 16 -1 (-750 4500)(-750 4325);
WIRE 16 -1 (-750 4500)(0 4500);
FORCEPROP 0 LAST CDS_PHYS_NET_NAME GND
J 0
(-725 4542);
PAINT MONO (-725 4542);
DISPLAY INVISIBLE (-725 4542);
WIRE 16 -1 (2100 6175)(2100 6050);
WIRE 16 -1 (2100 6175)(1975 6175);
WIRE 16 -1 (2225 6975)(2225 6925);
WIRE 16 -1 (3500 6675)(4825 6675);
FORCEPROP 2 LAST SIG_NAME JTAG_BMC_SW_TDO
J 0
(3890 6685);
DISPLAY 0.680851 (3890 6685);
PAINT WHITE (3890 6685);
WIRE 16 -1 (4825 6525)(3500 6525);
FORCEPROP 2 LAST SIG_NAME JTAG_BMC_SW_TDI
J 0
(3890 6535);
DISPLAY 0.680851 (3890 6535);
PAINT WHITE (3890 6535);
WIRE 16 -1 (3500 6225)(4825 6225);
FORCEPROP 2 LAST SIG_NAME JTAG_BMC_SW_TCK
J 0
(3890 6235);
DISPLAY 0.680851 (3890 6235);
PAINT WHITE (3890 6235);
WIRE 16 -1 (3500 6375)(4825 6375);
FORCEPROP 2 LAST SIG_NAME JTAG_BMC_SW_TMS
J 0
(3890 6385);
DISPLAY 0.680851 (3890 6385);
PAINT WHITE (3890 6385);
WIRE 16 -1 (1975 6225)(3300 6225);
FORCEPROP 2 LAST SIG_NAME JTAG_BMC_SW_TCK_R
J 0
(2115 6235);
DISPLAY 0.680851 (2115 6235);
PAINT WHITE (2115 6235);
WIRE 16 -1 (1975 6375)(3300 6375);
FORCEPROP 2 LAST SIG_NAME JTAG_BMC_SW_TMS_R
J 0
(2115 6385);
DISPLAY 0.680851 (2115 6385);
PAINT WHITE (2115 6385);
WIRE 16 -1 (3300 6525)(1975 6525);
FORCEPROP 2 LAST SIG_NAME JTAG_BMC_SW_TDI_R
J 0
(2115 6535);
DISPLAY 0.680851 (2115 6535);
PAINT WHITE (2115 6535);
WIRE 16 -1 (1975 6675)(3300 6675);
FORCEPROP 2 LAST SIG_NAME JTAG_BMC_SW_TDO_R
J 0
(2115 6685);
DISPLAY 0.680851 (2115 6685);
PAINT WHITE (2115 6685);
WIRE 16 -1 (2075 6725)(1975 6725);
WIRE 16 -1 (2075 7250)(2075 6725);
WIRE 16 -1 (2225 7250)(2075 7250);
WIRE 16 -1 (2225 7175)(2225 7250);
WIRE 16 -1 (1175 6625)(825 6625);
WIRE 16 -1 (825 6625)(825 6475);
WIRE 16 -1 (1175 6475)(825 6475);
WIRE 16 -1 (825 6475)(825 6325);
WIRE 16 -1 (1175 6325)(825 6325);
WIRE 16 -1 (825 5775)(-400 5775);
FORCEPROP 2 LAST SIG_NAME JTAG_BMC_SW_R_OE
J 0
(-60 5785);
DISPLAY 0.680851 (-60 5785);
PAINT WHITE (-60 5785);
WIRE 16 -1 (825 6175)(825 5775);
WIRE 16 -1 (825 6175)(825 6325);
WIRE 16 -1 (1175 6175)(825 6175);
WIRE 16 -1 (-150 6675)(1175 6675);
FORCEPROP 2 LAST SIG_NAME JTAG_BMC_TDO_R
J 0
(90 6685);
DISPLAY 0.680851 (90 6685);
PAINT WHITE (90 6685);
WIRE 16 -1 (1175 6525)(-150 6525);
FORCEPROP 2 LAST SIG_NAME JTAG_BMC_TDI_R
J 0
(90 6535);
DISPLAY 0.680851 (90 6535);
PAINT WHITE (90 6535);
WIRE 16 -1 (-150 6375)(1175 6375);
FORCEPROP 2 LAST SIG_NAME JTAG_BMC_TMS_R
J 0
(65 6385);
DISPLAY 0.680851 (65 6385);
PAINT WHITE (65 6385);
WIRE 16 -1 (-150 6225)(1175 6225);
FORCEPROP 2 LAST SIG_NAME JTAG_BMC_TCK_R
J 0
(65 6235);
DISPLAY 0.680851 (65 6235);
PAINT WHITE (65 6235);
WIRE 16 2175 (-100 4375)(1950 4375);
WIRE 16 2175 (1950 4975)(1950 4375);
WIRE 16 2175 (-100 4975)(-100 4375);
WIRE 16 2175 (-100 4975)(1950 4975);
WIRE 16 -1 (0 4550)(-1125 4550);
FORCEPROP 0 LAST CDS_PHYS_NET_NAME JTAG_BMC_SW_OE
J 0
(-750 4592);
PAINT MONO (-750 4592);
DISPLAY INVISIBLE (-750 4592);
WIRE 16 -1 (-1125 5775)(-1125 4550);
WIRE 16 -1 (-1125 5775)(-600 5775);
WIRE 16 -1 (-2225 5775)(-2225 5575);
WIRE 16 -1 (-2225 5775)(-1125 5775);
WIRE 16 -1 (-2250 5775)(-2225 5775);
WIRE 16 -1 (-2250 5900)(-2250 5775);
WIRE 16 -1 (-3025 5775)(-2250 5775);
FORCEPROP 2 LAST SIG_NAME JTAG_BMC_SW_OE
J 0
(-2910 5785);
DISPLAY 0.680851 (-2910 5785);
PAINT WHITE (-2910 5785);
WIRE 16 -1 (-750 4600)(-750 4750);
WIRE 16 -1 (0 4600)(-750 4600);
FORCEPROP 0 LAST CDS_PHYS_NET_NAME PU_JTAG_SW_PU
J 0
(-725 4642);
PAINT MONO (-725 4642);
DISPLAY INVISIBLE (-725 4642);
FORCEPROP 0 LAST SIG_NAME PU_JTAG_SW_PU
J 0
(-710 4610);
DISPLAY 0.680851 (-710 4610);
PAINT WHITE (-710 4610);
WIRE 16 -1 (-350 6525)(-1675 6525);
FORCEPROP 2 LAST SIG_NAME JTAG_BMC_TDI
J 0
(-1535 6535);
DISPLAY 0.680851 (-1535 6535);
PAINT WHITE (-1535 6535);
WIRE 16 -1 (-1675 6675)(-350 6675);
FORCEPROP 2 LAST SIG_NAME JTAG_BMC_TDO
J 0
(-1535 6685);
DISPLAY 0.680851 (-1535 6685);
PAINT WHITE (-1535 6685);
WIRE 16 -1 (-1675 6225)(-350 6225);
FORCEPROP 2 LAST SIG_NAME JTAG_BMC_TCK
J 0
(-1560 6235);
DISPLAY 0.680851 (-1560 6235);
PAINT WHITE (-1560 6235);
WIRE 16 -1 (-1675 6375)(-350 6375);
FORCEPROP 2 LAST SIG_NAME JTAG_BMC_TMS
J 0
(-1560 6385);
DISPLAY 0.680851 (-1560 6385);
PAINT WHITE (-1560 6385);
DOT 1 (-2225 5775);
DOT 1 (-2250 5775);
DOT 1 (-1125 5775);
DOT 1 (825 6175);
DOT 1 (825 6325);
DOT 1 (825 6475);
DOT 1 (2075 7250);
FORCENOTE
20220304 MODIFY FOR GT
(125 7600) 0;
DISPLAY LEFT (125 7600);
DISPLAY 2.510638 (125 7600);
PAINT PINK (125 7600);
FORCENOTE
JTAG SWITCH JUMPER
(875 4725) 0;
DISPLAY LEFT (875 4725);
DISPLAY 1.021277 (875 4725);
PAINT WHITE (875 4725);
FORCENOTE
1-2 CONTROL BY CPLD 
(875 4600) 0;
DISPLAY LEFT (875 4600);
DISPLAY 1.021277 (875 4600);
PAINT WHITE (875 4600);
FORCENOTE
2-3 DISABLE (DEFAULT)
(875 4475) 0;
DISPLAY LEFT (875 4475);
DISPLAY 1.021277 (875 4475);
PAINT WHITE (875 4475);
FORCENOTE
20221221 CHANGE JP16 JUMPER TO "2-3"
(50 4300) 0;
DISPLAY LEFT (50 4300);
DISPLAY 1.063830 (50 4300);
PAINT WHITE (50 4300);
QUIT
